# T6G (Grand Teton) — schematic netlist excerpt (pin names and nets, part order shuffled) for the footprints in the layout excerpt that follows; sources: Cadence DE-HDL packaged netlist, KiCad conversion of 04192023_DAF0TMB3IC0_F0TG_MB_C_brd_V02_OCP.brd

PR499  Q_RES  1.5 1% EMPTY  pkg 0402LF  page 195 : A = SW_PVDDCR_CPU0_P0_SW4_RC ; B = GND
C6586  Q_CAP_DIFFBUS  DIFF BUS_0.22UF 6.3V 20% X6S  pkg C0201  page 297 : \1\ = P5E_CPU0_P2_TX_BUF_C_DN<10> ; \2\ = P5E_CPU0_P2_TX_BUF_DN<10>

PD111  SS15P3SM386A  SS15P3S-M3/86A IC  pkg TO277A_4-3X6-1  page 262
  ANODE_1  = GND
  ANODE_2  = GND
  CATHODE  = P12V_AUX

C1547  Q_CAP_DIFFBUS  DIFF BUS_0.22UF 6.3V 20% X6S  pkg C0201  page 67 : \1\ = P5E_CPU1_P3_TX_C_DP<0> ; \2\ = P5E_CPU1_P3_TX_DP<0>

(kicad_pcb
	(version 20260206)
	(generator "pcbnew")
	(generator_version "10.0")
	(general
		(thickness 1.6)
		(legacy_teardrops no)
	)
	(paper "A4")
	(title_block
		(title "04192023_DAF0TMB3IC0_F0TG_MB_C_brd_V02_OCP.brd")
		(comment 1 "Grand Teton / footprints 1916-1919 of 8354")
	)
	(layers
		(0 "F.Cu" signal "TOP")
		(4 "In1.Cu" signal "GND")
		(6 "In2.Cu" signal "IN1")
		(8 "In3.Cu" signal "GND1")
		(10 "In4.Cu" signal "IN2")
		(12 "In5.Cu" signal "GND2")
		(14 "In6.Cu" signal "IN3")
		(16 "In7.Cu" signal "GND3")
		(18 "In8.Cu" signal "VCC")
		(20 "In9.Cu" signal "VCC1")
		(22 "In10.Cu" signal "GND4")
		(24 "In11.Cu" signal "IN4")
		(26 "In12.Cu" signal "GND5")
		(28 "In13.Cu" signal "IN5")
		(30 "In14.Cu" signal "GND6")
		(32 "In15.Cu" signal "IN6")
		(34 "In16.Cu" signal "GND7")
		(2 "B.Cu" signal "BOTTOM")
		(9 "F.Adhes" user "F.Adhesive")
		(11 "B.Adhes" user "B.Adhesive")
		(13 "F.Paste" user "Package Geometry/Pastemask Top")
		(15 "B.Paste" user "Package Geometry/Pastemask Bottom")
		(5 "F.SilkS" user "Ref Des/Silkscreen Top")
		(7 "B.SilkS" user "Ref Des/Silkscreen Bottom")
		(1 "F.Mask" user "Board Geometry/Soldermask Top")
		(3 "B.Mask" user "Board Geometry/Soldermask Bottom")
		(17 "Dwgs.User" user "User.Drawings")
		(19 "Cmts.User" user "User.Comments")
		(21 "Eco1.User" user "User.Eco1")
		(23 "Eco2.User" user "User.Eco2")
		(25 "Edge.Cuts" user "Board Geometry/Outline")
		(27 "Margin" user)
		(31 "F.CrtYd" user "Package Geometry/Place Bound Top")
		(29 "B.CrtYd" user "Package Geometry/Place Bound Bottom")
		(35 "F.Fab" user "Ref Des/Assembly Top")
		(33 "B.Fab" user "Ref Des/Assembly Bottom")
	)
	(footprint ""
		(layer "F.Cu")
		(at 215.74379 -390.377934 90)
		(property "Reference" "PD111"
			(at 1.8034 -3.343148 90)
			(unlocked yes)
			(layer "F.SilkS")
			(effects
				(font
					(size 0.7874 0.5842)
					(thickness 0.1524)
				)
			)
		)
		(property "Value" ""
			(at 0 0 90)
			(layer "F.Fab")
			(effects
				(font
					(size 1.27 1.27)
				)
			)
		)
		(duplicate_pad_numbers_are_jumpers no)
		(fp_line
			(start 3.541776 -2.54)
			(end 3.541776 2.54)
			(stroke
				(width 0.1524)
				(type default)
			)
			(layer "F.SilkS")
		)
		(fp_line
			(start -3.539744 -2.54)
			(end 3.541776 -2.54)
			(stroke
				(width 0.1524)
				(type default)
			)
			(layer "F.SilkS")
		)
		(fp_line
			(start 3.541776 2.54)
			(end -3.539744 2.54)
			(stroke
				(width 0.1524)
				(type default)
			)
			(layer "F.SilkS")
		)
		(fp_line
			(start -3.539744 2.54)
			(end -3.539744 -2.54)
			(stroke
				(width 0.1524)
				(type default)
			)
			(layer "F.SilkS")
		)
		(fp_poly
			(pts
				(xy -5.651246 1.802892) (xy -5.651246 0.786892) (xy -4.635246 1.294892)
			)
			(stroke
				(width 0)
				(type default)
			)
			(fill yes)
			(layer "F.SilkS")
		)
		(fp_line
			(start 3.074924 -2.175002)
			(end 3.074924 2.175002)
			(stroke
				(width 0.1)
				(type default)
			)
			(layer "F.Fab")
		)
		(fp_line
			(start -3.074924 -2.175002)
			(end 3.074924 -2.175002)
			(stroke
				(width 0.1)
				(type default)
			)
			(layer "F.Fab")
		)
		(fp_line
			(start 3.074924 2.175002)
			(end -3.074924 2.175002)
			(stroke
				(width 0.1)
				(type default)
			)
			(layer "F.Fab")
		)
		(fp_line
			(start -3.074924 2.175002)
			(end -3.074924 -2.175002)
			(stroke
				(width 0.1)
				(type default)
			)
			(layer "F.Fab")
		)
		(fp_poly
			(pts
				(xy -4.699 0.531876) (xy -4.699 1.547876) (xy -3.683 1.039876)
			)
			(stroke
				(width 0)
				(type default)
			)
			(fill yes)
			(layer "F.Fab")
		)
		(pad "1" smd rect
			(at -2.765044 1.039876 270)
			(size 1.27 1.4224)
			(layers "F.Cu" "F.Mask" "F.Paste")
			(net "GND")
		)
		(pad "2" smd rect
			(at -2.765044 -1.039876 270)
			(size 1.27 1.4224)
			(layers "F.Cu" "F.Mask" "F.Paste")
			(net "GND")
		)
		(pad "K" smd rect
			(at 1.039876 0 270)
			(size 4.7244 4.8006)
			(layers "F.Cu" "F.Mask" "F.Paste")
			(net "P12V_AUX")
		)
	)
	(footprint ""
		(layer "F.Cu")
		(at 393.086336 -184.478168 -90)
		(property "Reference" "PR499"
			(at 0 0 270)
			(layer "F.SilkS")
			(hide yes)
			(effects
				(font
					(size 1.27 1.27)
				)
			)
		)
		(property "Value" ""
			(at 0 0 270)
			(layer "F.Fab")
			(effects
				(font
					(size 1.27 1.27)
				)
			)
		)
		(duplicate_pad_numbers_are_jumpers no)
		(fp_line
			(start -0.7874 0.4064)
			(end -0.7874 -0.4064)
			(stroke
				(width 0.1524)
				(type default)
			)
			(layer "F.SilkS")
		)
		(fp_line
			(start 0.7874 0.4064)
			(end -0.7874 0.4064)
			(stroke
				(width 0.1524)
				(type default)
			)
			(layer "F.SilkS")
		)
		(fp_line
			(start -0.7874 -0.4064)
			(end 0.7874 -0.4064)
			(stroke
				(width 0.1524)
				(type default)
			)
			(layer "F.SilkS")
		)
		(fp_line
			(start 0.7874 -0.4064)
			(end 0.7874 0.4064)
			(stroke
				(width 0.1524)
				(type default)
			)
			(layer "F.SilkS")
		)
		(fp_line
			(start -0.67945 0.3048)
			(end -0.67945 -0.305054)
			(stroke
				(width 0.1)
				(type default)
			)
			(layer "F.Fab")
		)
		(fp_line
			(start -0.12065 0.3048)
			(end -0.67945 0.3048)
			(stroke
				(width 0.1)
				(type default)
			)
			(layer "F.Fab")
		)
		(fp_line
			(start 0.120396 0.3048)
			(end 0.120396 0.2794)
			(stroke
				(width 0.1)
				(type default)
			)
			(layer "F.Fab")
		)
		(fp_line
			(start 0.67945 0.3048)
			(end 0.120396 0.3048)
			(stroke
				(width 0.1)
				(type default)
			)
			(layer "F.Fab")
		)
		(fp_line
			(start -0.12065 0.2794)
			(end -0.12065 0.3048)
			(stroke
				(width 0.1)
				(type default)
			)
			(layer "F.Fab")
		)
		(fp_line
			(start 0.120396 0.2794)
			(end -0.12065 0.2794)
			(stroke
				(width 0.1)
				(type default)
			)
			(layer "F.Fab")
		)
		(fp_line
			(start -0.12065 -0.2794)
			(end 0.12065 -0.2794)
			(stroke
				(width 0.1)
				(type default)
			)
			(layer "F.Fab")
		)
		(fp_line
			(start 0.12065 -0.2794)
			(end 0.12065 -0.3048)
			(stroke
				(width 0.1)
				(type default)
			)
			(layer "F.Fab")
		)
		(fp_line
			(start 0.12065 -0.3048)
			(end 0.67945 -0.3048)
			(stroke
				(width 0.1)
				(type default)
			)
			(layer "F.Fab")
		)
		(fp_line
			(start 0.67945 -0.3048)
			(end 0.67945 0.3048)
			(stroke
				(width 0.1)
				(type default)
			)
			(layer "F.Fab")
		)
		(fp_line
			(start -0.67945 -0.305054)
			(end -0.12065 -0.305054)
			(stroke
				(width 0.1)
				(type default)
			)
			(layer "F.Fab")
		)
		(fp_line
			(start -0.12065 -0.305054)
			(end -0.12065 -0.2794)
			(stroke
				(width 0.1)
				(type default)
			)
			(layer "F.Fab")
		)
		(pad "1" smd circle
			(at -0.40005 0 270)
			(size 0 0)
			(layers "F.Cu" "F.Mask" "F.Paste")
			(net "SW_PVDDCR_CPU0_P0_SW4_RC")
		)
		(pad "2" smd circle
			(at 0.40005 0 270)
			(size 0 0)
			(layers "F.Cu" "F.Mask" "F.Paste")
			(net "GND")
		)
	)
	(footprint ""
		(layer "F.Cu")
		(at 401.501102 -416.899344 -90)
		(property "Reference" "C6586"
			(at 0 0 270)
			(layer "F.SilkS")
			(hide yes)
			(effects
				(font
					(size 1.27 1.27)
				)
			)
		)
		(property "Value" ""
			(at 0 0 270)
			(layer "F.Fab")
			(effects
				(font
					(size 1.27 1.27)
				)
			)
		)
		(duplicate_pad_numbers_are_jumpers no)
		(fp_line
			(start -0.299974 0.150114)
			(end -0.299974 -0.150114)
			(stroke
				(width 0.1)
				(type default)
			)
			(layer "F.Fab")
		)
		(fp_line
			(start 0.299974 0.150114)
			(end -0.299974 0.150114)
			(stroke
				(width 0.1)
				(type default)
			)
			(layer "F.Fab")
		)
		(fp_line
			(start -0.299974 -0.150114)
			(end 0.299974 -0.150114)
			(stroke
				(width 0.1)
				(type default)
			)
			(layer "F.Fab")
		)
		(fp_line
			(start 0.299974 -0.150114)
			(end 0.299974 0.150114)
			(stroke
				(width 0.1)
				(type default)
			)
			(layer "F.Fab")
		)
		(pad "1" smd rect
			(at -0.2667 0 270)
			(size 0.3048 0.381)
			(layers "F.Cu" "F.Mask" "F.Paste")
			(net "P5E_CPU0_P2_TX_BUF_C_DN<10>")
		)
		(pad "2" smd rect
			(at 0.2667 0 270)
			(size 0.3048 0.381)
			(layers "F.Cu" "F.Mask" "F.Paste")
			(net "P5E_CPU0_P2_TX_BUF_DN<10>")
		)
	)
	(footprint ""
		(layer "F.Cu")
		(at 110.067344 -382.39446 180)
		(property "Reference" "C1547"
			(at 0 0 180)
			(layer "F.SilkS")
			(hide yes)
			(effects
				(font
					(size 1.27 1.27)
				)
			)
		)
		(property "Value" ""
			(at 0 0 180)
			(layer "F.Fab")
			(effects
				(font
					(size 1.27 1.27)
				)
			)
		)
		(duplicate_pad_numbers_are_jumpers no)
		(fp_line
			(start 0.299974 0.150114)
			(end -0.299974 0.150114)
			(stroke
				(width 0.1)
				(type default)
			)
			(layer "F.Fab")
		)
		(fp_line
			(start 0.299974 -0.150114)
			(end 0.299974 0.150114)
			(stroke
				(width 0.1)
				(type default)
			)
			(layer "F.Fab")
		)
		(fp_line
			(start -0.299974 0.150114)
			(end -0.299974 -0.150114)
			(stroke
				(width 0.1)
				(type default)
			)
			(layer "F.Fab")
		)
		(fp_line
			(start -0.299974 -0.150114)
			(end 0.299974 -0.150114)
			(stroke
				(width 0.1)
				(type default)
			)
			(layer "F.Fab")
		)
		(pad "1" smd rect
			(at -0.2667 0 180)
			(size 0.3048 0.381)
			(layers "F.Cu" "F.Mask" "F.Paste")
			(net "P5E_CPU1_P3_TX_C_DP<0>")
		)
		(pad "2" smd rect
			(at 0.2667 0 180)
			(size 0.3048 0.381)
			(layers "F.Cu" "F.Mask" "F.Paste")
			(net "P5E_CPU1_P3_TX_DP<0>")
		)
	)
)
